# TIMECARD (Time Appliance Project (Time Card)) — schematic netlist excerpt (pin names and nets, part order shuffled) for the footprints in the layout excerpt that follows; sources: Cadence DE-HDL packaged netlist, KiCad conversion of R4006-B0001-02_R01.brd

R356  RESISTOR  0OHM -  pkg SMC_0402R_H016  page 9 : \1\ = BF_PCIE_PERST_N ; \2\ = FPGA_PROGRAM_N

(kicad_pcb
	(version 20260206)
	(generator "pcbnew")
	(generator_version "10.0")
	(general
		(thickness 1.6)
		(legacy_teardrops no)
	)
	(paper "A4")
	(title_block
		(title "timecard-production-celestica-r4006 — R4006-B0001-02_R01.brd")
		(comment 1 "Time Appliance Project (Time Card) / footprints 198-198 of 1113")
	)
	(layers
		(0 "F.Cu" signal "TOP")
		(4 "In1.Cu" signal "L02_GND1")
		(6 "In2.Cu" signal "L03_SIG1")
		(8 "In3.Cu" signal "L04_GND2")
		(10 "In4.Cu" signal "L05_VCC1")
		(12 "In5.Cu" signal "L06_VCC2")
		(14 "In6.Cu" signal "L07_GND3")
		(16 "In7.Cu" signal "L08_SIG2")
		(18 "In8.Cu" signal "L09_GND4")
		(2 "B.Cu" signal "BOTTOM")
		(9 "F.Adhes" user "F.Adhesive")
		(11 "B.Adhes" user "B.Adhesive")
		(13 "F.Paste" user "Package Geometry/Pastemask Top")
		(15 "B.Paste" user "Package Geometry/Pastemask Bottom")
		(5 "F.SilkS" user "Ref Des/Silkscreen Top")
		(7 "B.SilkS" user "Ref Des/Silkscreen Bottom")
		(1 "F.Mask" user "Board Geometry/Soldermask Top")
		(3 "B.Mask" user "Board Geometry/Soldermask Bottom")
		(17 "Dwgs.User" user "User.Drawings")
		(19 "Cmts.User" user "User.Comments")
		(21 "Eco1.User" user "User.Eco1")
		(23 "Eco2.User" user "User.Eco2")
		(25 "Edge.Cuts" user "Board Geometry/Outline")
		(27 "Margin" user)
		(31 "F.CrtYd" user "Package Geometry/Place Bound Top")
		(29 "B.CrtYd" user "Package Geometry/Place Bound Bottom")
		(35 "F.Fab" user "Ref Des/Assembly Top")
		(33 "B.Fab" user "Ref Des/Assembly Bottom")
	)
	(footprint ""
		(layer "F.Cu")
		(at 124.587 -52.578 180)
		(property "Reference" "R356"
			(at -3.175 -0.16637 0)
			(unlocked yes)
			(layer "F.SilkS")
			(effects
				(font
					(size 0.7874 0.5842)
					(thickness 0.1524)
				)
			)
		)
		(property "Value" "VAL*"
			(at 0.02032 2.13233 180)
			(unlocked yes)
			(layer "F.Fab")
			(hide yes)
			(effects
				(font
					(size 0.7874 0.5842)
					(thickness 0.1524)
				)
			)
		)
		(property "Tolerance" "TOL*"
			(at 0.044704 3.05435 180)
			(unlocked yes)
			(layer "Cmts.User")
			(hide yes)
			(effects
				(font
					(size 0.7874 0.5842)
					(thickness 0.1524)
				)
			)
		)
		(property "User Part Number" "PARTNUM*"
			(at 0.02032 4.024884 180)
			(unlocked yes)
			(layer "Cmts.User")
			(hide yes)
			(effects
				(font
					(size 0.7874 0.5842)
					(thickness 0.1524)
				)
			)
		)
		(property "Device Type" "RESISTOR-G155-100R0-J0,0OHM,-"
			(at 0.008382 1.210564 180)
			(unlocked yes)
			(layer "F.Fab")
			(hide yes)
			(effects
				(font
					(size 0.7874 0.5842)
					(thickness 0.1524)
				)
			)
		)
		(duplicate_pad_numbers_are_jumpers no)
		(fp_line
			(start 1.143 0.5588)
			(end 1.143 -0.5588)
			(stroke
				(width 0.1)
				(type default)
			)
			(layer "F.SilkS")
		)
		(fp_line
			(start 1.143 -0.5588)
			(end -1.143 -0.5588)
			(stroke
				(width 0.1)
				(type default)
			)
			(layer "F.SilkS")
		)
		(fp_line
			(start -1.143 0.5588)
			(end 1.143 0.5588)
			(stroke
				(width 0.1)
				(type default)
			)
			(layer "F.SilkS")
		)
		(fp_line
			(start -1.143 -0.5588)
			(end -1.143 0.5588)
			(stroke
				(width 0.1)
				(type default)
			)
			(layer "F.SilkS")
		)
		(fp_poly
			(pts
				(xy -1.143 0.5588) (xy 1.143 0.5588) (xy 1.143 -0.5588) (xy -1.143 -0.5588)
			)
			(stroke
				(width 0)
				(type default)
			)
			(fill no)
			(layer "F.CrtYd")
		)
		(fp_line
			(start 0.508 0.3048)
			(end 0.508 -0.3048)
			(stroke
				(width 0.1)
				(type default)
			)
			(layer "F.Fab")
		)
		(fp_line
			(start 0.508 -0.3048)
			(end -0.508 -0.3048)
			(stroke
				(width 0.1)
				(type default)
			)
			(layer "F.Fab")
		)
		(fp_line
			(start -0.508 0.3048)
			(end 0.508 0.3048)
			(stroke
				(width 0.1)
				(type default)
			)
			(layer "F.Fab")
		)
		(fp_line
			(start -0.508 -0.3048)
			(end -0.508 0.3048)
			(stroke
				(width 0.1)
				(type default)
			)
			(layer "F.Fab")
		)
		(pad "1" smd rect
			(at -0.5334 0 180)
			(size 0.7112 0.6096)
			(layers "F.Cu" "F.Mask" "F.Paste")
			(net "BF_PCIE_PERST_N")
		)
		(pad "2" smd rect
			(at 0.5334 0 180)
			(size 0.7112 0.6096)
			(layers "F.Cu" "F.Mask" "F.Paste")
			(net "FPGA_PROGRAM_N")
		)
		(zone
			(layer "F.Cu")
			(hatch none 0.5)
			(connect_pads
				(clearance 0)
			)
			(min_thickness 0.25)
			(keepout
				(tracks not_allowed)
				(vias allowed)
				(pads allowed)
				(copperpour not_allowed)
				(footprints allowed)
			)
			(placement
				(enabled no)
				(sheetname "")
			)
			(fill
				(thermal_gap 0.5)
				(thermal_bridge_width 0.5)
				(island_removal_mode 0)
			)
			(polygon
				(pts
					(xy 124.6632 -52.8828) (xy 124.5108 -52.8828) (xy 124.5108 -52.2732) (xy 124.6632 -52.2732)
				)
			)
		)
		(zone
			(layer "F.Cu")
			(hatch none 0.5)
			(connect_pads
				(clearance 0)
			)
			(min_thickness 0.25)
			(keepout
				(tracks allowed)
				(vias not_allowed)
				(pads allowed)
				(copperpour not_allowed)
				(footprints allowed)
			)
			(placement
				(enabled no)
				(sheetname "")
			)
			(fill
				(thermal_gap 0.5)
				(thermal_bridge_width 0.5)
				(island_removal_mode 0)
			)
			(polygon
				(pts
					(xy 124.6632 -52.8828) (xy 124.5108 -52.8828) (xy 124.5108 -52.2732) (xy 124.6632 -52.2732)
				)
			)
		)
	)
)
